(kicad_pcb
	(version 20260206)
	(generator "pcbnew")
	(generator_version "10.0")
	(general
		(thickness 1.6)
		(legacy_teardrops no)
	)
	(paper "A4")
	(title_block
		(title "Wiwynn_Tioga_Pass_MB.brd")
		(comment 1 "Tioga Pass / footprints 4754-4761 of 4770")
	)
	(layers
		(0 "F.Cu" signal "TOP")
		(4 "In1.Cu" signal "L2GND")
		(6 "In2.Cu" signal "L3")
		(8 "In3.Cu" signal "L4GND")
		(10 "In4.Cu" signal "L5")
		(12 "In5.Cu" signal "L6GND")
		(14 "In6.Cu" signal "L7VCC")
		(16 "In7.Cu" signal "L8VCC")
		(18 "In8.Cu" signal "L9GND")
		(20 "In9.Cu" signal "L10")
		(22 "In10.Cu" signal "L11GND")
		(24 "In11.Cu" signal "L12")
		(26 "In12.Cu" signal "L13GND")
		(2 "B.Cu" signal "BOTTOM")
		(9 "F.Adhes" user "F.Adhesive")
		(11 "B.Adhes" user "B.Adhesive")
		(13 "F.Paste" user "Package Geometry/Pastemask Top")
		(15 "B.Paste" user "Package Geometry/Pastemask Bottom")
		(5 "F.SilkS" user "Ref Des/Silkscreen Top")
		(7 "B.SilkS" user "Ref Des/Silkscreen Bottom")
		(1 "F.Mask" user "Board Geometry/Soldermask Top")
		(3 "B.Mask" user "Board Geometry/Soldermask Bottom")
		(17 "Dwgs.User" user "User.Drawings")
		(19 "Cmts.User" user "User.Comments")
		(21 "Eco1.User" user "User.Eco1")
		(23 "Eco2.User" user "User.Eco2")
		(25 "Edge.Cuts" user "Board Geometry/Outline")
		(27 "Margin" user)
		(31 "F.CrtYd" user "Package Geometry/Place Bound Top")
		(29 "B.CrtYd" user "Package Geometry/Place Bound Bottom")
		(35 "F.Fab" user "Ref Des/Assembly Top")
		(33 "B.Fab" user "Ref Des/Assembly Bottom")
	)
	(footprint ""
		(layer "B.Cu")
		(at 446.33388 -64.752982 180)
		(property "Reference" "C2P12"
			(at 0 0 0)
			(layer "B.SilkS")
			(hide yes)
			(effects
				(font
					(size 1.27 1.27)
				)
				(justify mirror)
			)
		)
		(property "Value" ""
			(at 0 0 0)
			(layer "B.Fab")
			(effects
				(font
					(size 1.27 1.27)
				)
				(justify mirror)
			)
		)
		(duplicate_pad_numbers_are_jumpers no)
		(fp_poly
			(pts
				(xy -0.3048 -0.1016) (xy -0.3048 0.9906) (xy 0.3048 0.9906) (xy 0.3048 -0.1016)
			)
			(stroke
				(width 0)
				(type default)
			)
			(fill no)
			(layer "B.CrtYd")
		)
		(fp_line
			(start 0.3048 0.9906)
			(end -0.3048 0.9906)
			(stroke
				(width 0.1)
				(type default)
			)
			(layer "B.Fab")
		)
		(fp_line
			(start 0.3048 -0.1016)
			(end 0.3048 0.9906)
			(stroke
				(width 0.1)
				(type default)
			)
			(layer "B.Fab")
		)
		(fp_line
			(start -0.3048 0.9906)
			(end -0.3048 -0.1016)
			(stroke
				(width 0.1)
				(type default)
			)
			(layer "B.Fab")
		)
		(fp_line
			(start -0.3048 -0.1016)
			(end 0.3048 -0.1016)
			(stroke
				(width 0.1)
				(type default)
			)
			(layer "B.Fab")
		)
		(pad "1" smd rect
			(at 0 0)
			(size 0.508 0.508)
			(layers "B.Cu" "B.Mask" "B.Paste")
			(net "P12V_STBY")
		)
		(pad "2" smd rect
			(at 0 0.889)
			(size 0.508 0.508)
			(layers "B.Cu" "B.Mask" "B.Paste")
			(net "GND")
		)
		(zone
			(layer "B.Cu")
			(hatch none 0.5)
			(connect_pads
				(clearance 0)
			)
			(min_thickness 0.25)
			(keepout
				(tracks not_allowed)
				(vias allowed)
				(pads allowed)
				(copperpour not_allowed)
				(footprints allowed)
			)
			(placement
				(enabled no)
				(sheetname "")
			)
			(fill
				(thermal_gap 0.5)
				(thermal_bridge_width 0.5)
				(island_removal_mode 0)
			)
			(polygon
				(pts
					(xy 446.07988 -65.387982) (xy 446.58788 -65.387982) (xy 446.58788 -65.006982) (xy 446.07988 -65.006982)
				)
			)
		)
		(zone
			(layer "B.Cu")
			(hatch none 0.5)
			(connect_pads
				(clearance 0)
			)
			(min_thickness 0.25)
			(keepout
				(tracks allowed)
				(vias not_allowed)
				(pads allowed)
				(copperpour not_allowed)
				(footprints allowed)
			)
			(placement
				(enabled no)
				(sheetname "")
			)
			(fill
				(thermal_gap 0.5)
				(thermal_bridge_width 0.5)
				(island_removal_mode 0)
			)
			(polygon
				(pts
					(xy 446.07988 -65.006982) (xy 446.58788 -65.006982) (xy 446.58788 -65.387982) (xy 446.07988 -65.387982)
				)
			)
		)
	)
	(footprint ""
		(layer "B.Cu")
		(at 269.775686 -68.17614 180)
		(property "Reference" "C5P43"
			(at 0 0 0)
			(layer "B.SilkS")
			(hide yes)
			(effects
				(font
					(size 1.27 1.27)
				)
				(justify mirror)
			)
		)
		(property "Value" ""
			(at 0 0 0)
			(layer "B.Fab")
			(effects
				(font
					(size 1.27 1.27)
				)
				(justify mirror)
			)
		)
		(duplicate_pad_numbers_are_jumpers no)
		(fp_poly
			(pts
				(xy 0.7239 -0.2159) (xy -0.7239 -0.2159) (xy -0.7239 1.9939) (xy 0.7239 1.9939)
			)
			(stroke
				(width 0)
				(type default)
			)
			(fill no)
			(layer "B.CrtYd")
		)
		(fp_line
			(start 0.7239 1.9939)
			(end -0.7239 1.9939)
			(stroke
				(width 0.1)
				(type default)
			)
			(layer "B.Fab")
		)
		(fp_line
			(start 0.7239 -0.2159)
			(end 0.7239 1.9939)
			(stroke
				(width 0.1)
				(type default)
			)
			(layer "B.Fab")
		)
		(fp_line
			(start -0.7239 1.9939)
			(end -0.7239 -0.2159)
			(stroke
				(width 0.1)
				(type default)
			)
			(layer "B.Fab")
		)
		(fp_line
			(start -0.7239 -0.2159)
			(end 0.7239 -0.2159)
			(stroke
				(width 0.1)
				(type default)
			)
			(layer "B.Fab")
		)
		(pad "1" smd rect
			(at 0 0)
			(size 1.27 1.016)
			(layers "B.Cu" "B.Mask" "B.Paste")
			(net "PVDDQ_ABC")
		)
		(pad "2" smd rect
			(at 0 1.778)
			(size 1.27 1.016)
			(layers "B.Cu" "B.Mask" "B.Paste")
			(net "GND")
		)
		(zone
			(layer "B.Cu")
			(hatch none 0.5)
			(connect_pads
				(clearance 0)
			)
			(min_thickness 0.25)
			(keepout
				(tracks not_allowed)
				(vias allowed)
				(pads allowed)
				(copperpour not_allowed)
				(footprints allowed)
			)
			(placement
				(enabled no)
				(sheetname "")
			)
			(fill
				(thermal_gap 0.5)
				(thermal_bridge_width 0.5)
				(island_removal_mode 0)
			)
			(polygon
				(pts
					(xy 269.140686 -68.68414) (xy 270.410686 -68.68414) (xy 270.410686 -69.44614) (xy 269.140686 -69.44614)
				)
			)
		)
	)
	(footprint ""
		(layer "B.Cu")
		(at 252.1585 -140.208 -90)
		(property "Reference" "C5G66"
			(at -1.14681 0.76708 0)
			(unlocked yes)
			(layer "B.SilkS")
			(effects
				(font
					(size 0.7874 0.5842)
					(thickness 0.1524)
				)
				(justify mirror)
			)
		)
		(property "Value" ""
			(at 0 0 90)
			(layer "B.Fab")
			(effects
				(font
					(size 1.27 1.27)
				)
				(justify mirror)
			)
		)
		(duplicate_pad_numbers_are_jumpers no)
		(fp_rect
			(start 0.4953 1.6002)
			(end -0.4953 -0.2032)
			(stroke
				(width 0)
				(type default)
			)
			(fill no)
			(layer "B.CrtYd")
		)
		(fp_line
			(start -0.4953 1.6002)
			(end 0.4953 1.6002)
			(stroke
				(width 0.1)
				(type default)
			)
			(layer "B.Fab")
		)
		(fp_line
			(start 0.4953 1.6002)
			(end 0.4953 -0.2032)
			(stroke
				(width 0.1)
				(type default)
			)
			(layer "B.Fab")
		)
		(fp_line
			(start -0.4953 -0.2032)
			(end -0.4953 1.6002)
			(stroke
				(width 0.1)
				(type default)
			)
			(layer "B.Fab")
		)
		(fp_line
			(start 0.4953 -0.2032)
			(end -0.4953 -0.2032)
			(stroke
				(width 0.1)
				(type default)
			)
			(layer "B.Fab")
		)
		(pad "1" smd rect
			(at 0 0 90)
			(size 0.762 0.889)
			(layers "B.Cu" "B.Mask" "B.Paste")
			(net "PVDDQ_DEF")
		)
		(pad "2" smd rect
			(at 0 1.397 90)
			(size 0.762 0.889)
			(layers "B.Cu" "B.Mask" "B.Paste")
			(net "GND")
		)
		(zone
			(layer "B.Cu")
			(hatch none 0.5)
			(connect_pads
				(clearance 0)
			)
			(min_thickness 0.25)
			(keepout
				(tracks not_allowed)
				(vias allowed)
				(pads allowed)
				(copperpour not_allowed)
				(footprints allowed)
			)
			(placement
				(enabled no)
				(sheetname "")
			)
			(fill
				(thermal_gap 0.5)
				(thermal_bridge_width 0.5)
				(island_removal_mode 0)
			)
			(polygon
				(pts
					(xy 251.206 -139.827) (xy 251.714 -139.827) (xy 251.714 -140.589) (xy 251.206 -140.589)
				)
			)
		)
	)
	(footprint ""
		(layer "B.Cu")
		(at 421.513 -147.828 -90)
		(property "Reference" "C2L22"
			(at 0 0 90)
			(layer "B.SilkS")
			(hide yes)
			(effects
				(font
					(size 1.27 1.27)
				)
				(justify mirror)
			)
		)
		(property "Value" ""
			(at 0 0 90)
			(layer "B.Fab")
			(effects
				(font
					(size 1.27 1.27)
				)
				(justify mirror)
			)
		)
		(duplicate_pad_numbers_are_jumpers no)
		(fp_poly
			(pts
				(xy -0.3048 -0.1016) (xy -0.3048 0.9906) (xy 0.3048 0.9906) (xy 0.3048 -0.1016)
			)
			(stroke
				(width 0)
				(type default)
			)
			(fill no)
			(layer "B.CrtYd")
		)
		(fp_line
			(start -0.3048 0.9906)
			(end -0.3048 -0.1016)
			(stroke
				(width 0.1)
				(type default)
			)
			(layer "B.Fab")
		)
		(fp_line
			(start 0.3048 0.9906)
			(end -0.3048 0.9906)
			(stroke
				(width 0.1)
				(type default)
			)
			(layer "B.Fab")
		)
		(fp_line
			(start -0.3048 -0.1016)
			(end 0.3048 -0.1016)
			(stroke
				(width 0.1)
				(type default)
			)
			(layer "B.Fab")
		)
		(fp_line
			(start 0.3048 -0.1016)
			(end 0.3048 0.9906)
			(stroke
				(width 0.1)
				(type default)
			)
			(layer "B.Fab")
		)
		(pad "1" smd rect
			(at 0 0 90)
			(size 0.508 0.508)
			(layers "B.Cu" "B.Mask" "B.Paste")
			(net "SATA6G_P3_TX_C_DN")
		)
		(pad "2" smd rect
			(at 0 0.889 90)
			(size 0.508 0.508)
			(layers "B.Cu" "B.Mask" "B.Paste")
			(net "SATA6G_PCH_PCIE_UP_SATA_TXN<3>")
		)
		(zone
			(layer "B.Cu")
			(hatch none 0.5)
			(connect_pads
				(clearance 0)
			)
			(min_thickness 0.25)
			(keepout
				(tracks not_allowed)
				(vias allowed)
				(pads allowed)
				(copperpour not_allowed)
				(footprints allowed)
			)
			(placement
				(enabled no)
				(sheetname "")
			)
			(fill
				(thermal_gap 0.5)
				(thermal_bridge_width 0.5)
				(island_removal_mode 0)
			)
			(polygon
				(pts
					(xy 420.878 -147.574) (xy 420.878 -148.082) (xy 421.259 -148.082) (xy 421.259 -147.574)
				)
			)
		)
		(zone
			(layer "B.Cu")
			(hatch none 0.5)
			(connect_pads
				(clearance 0)
			)
			(min_thickness 0.25)
			(keepout
				(tracks allowed)
				(vias not_allowed)
				(pads allowed)
				(copperpour not_allowed)
				(footprints allowed)
			)
			(placement
				(enabled no)
				(sheetname "")
			)
			(fill
				(thermal_gap 0.5)
				(thermal_bridge_width 0.5)
				(island_removal_mode 0)
			)
			(polygon
				(pts
					(xy 421.259 -147.574) (xy 421.259 -148.082) (xy 420.878 -148.082) (xy 420.878 -147.574)
				)
			)
		)
	)
	(footprint ""
		(layer "B.Cu")
		(at 181.9656 -135.9662 180)
		(property "Reference" "C6L11"
			(at 0 0 0)
			(layer "B.SilkS")
			(hide yes)
			(effects
				(font
					(size 1.27 1.27)
				)
				(justify mirror)
			)
		)
		(property "Value" ""
			(at 0 0 0)
			(layer "B.Fab")
			(effects
				(font
					(size 1.27 1.27)
				)
				(justify mirror)
			)
		)
		(duplicate_pad_numbers_are_jumpers no)
		(fp_poly
			(pts
				(xy -0.3048 -0.1016) (xy -0.3048 0.9906) (xy 0.3048 0.9906) (xy 0.3048 -0.1016)
			)
			(stroke
				(width 0)
				(type default)
			)
			(fill no)
			(layer "B.CrtYd")
		)
		(fp_line
			(start 0.3048 0.9906)
			(end -0.3048 0.9906)
			(stroke
				(width 0.1)
				(type default)
			)
			(layer "B.Fab")
		)
		(fp_line
			(start 0.3048 -0.1016)
			(end 0.3048 0.9906)
			(stroke
				(width 0.1)
				(type default)
			)
			(layer "B.Fab")
		)
		(fp_line
			(start -0.3048 0.9906)
			(end -0.3048 -0.1016)
			(stroke
				(width 0.1)
				(type default)
			)
			(layer "B.Fab")
		)
		(fp_line
			(start -0.3048 -0.1016)
			(end 0.3048 -0.1016)
			(stroke
				(width 0.1)
				(type default)
			)
			(layer "B.Fab")
		)
		(pad "1" smd rect
			(at 0 0)
			(size 0.508 0.508)
			(layers "B.Cu" "B.Mask" "B.Paste")
			(net "VR_FET_SW_P12V_STBY_PVPP_KLM")
		)
		(pad "2" smd rect
			(at 0 0.889)
			(size 0.508 0.508)
			(layers "B.Cu" "B.Mask" "B.Paste")
			(net "GND")
		)
		(zone
			(layer "B.Cu")
			(hatch none 0.5)
			(connect_pads
				(clearance 0)
			)
			(min_thickness 0.25)
			(keepout
				(tracks not_allowed)
				(vias allowed)
				(pads allowed)
				(copperpour not_allowed)
				(footprints allowed)
			)
			(placement
				(enabled no)
				(sheetname "")
			)
			(fill
				(thermal_gap 0.5)
				(thermal_bridge_width 0.5)
				(island_removal_mode 0)
			)
			(polygon
				(pts
					(xy 181.7116 -136.6012) (xy 182.2196 -136.6012) (xy 182.2196 -136.2202) (xy 181.7116 -136.2202)
				)
			)
		)
		(zone
			(layer "B.Cu")
			(hatch none 0.5)
			(connect_pads
				(clearance 0)
			)
			(min_thickness 0.25)
			(keepout
				(tracks allowed)
				(vias not_allowed)
				(pads allowed)
				(copperpour not_allowed)
				(footprints allowed)
			)
			(placement
				(enabled no)
				(sheetname "")
			)
			(fill
				(thermal_gap 0.5)
				(thermal_bridge_width 0.5)
				(island_removal_mode 0)
			)
			(polygon
				(pts
					(xy 181.7116 -136.2202) (xy 182.2196 -136.2202) (xy 182.2196 -136.6012) (xy 181.7116 -136.6012)
				)
			)
		)
	)
	(footprint ""
		(layer "B.Cu")
		(at 464.33486 -41.18102)
		(property "Reference" "C9W14"
			(at -0.97536 0.76708 90)
			(unlocked yes)
			(layer "B.SilkS")
			(effects
				(font
					(size 0.4064 0.254)
					(thickness 0.1524)
				)
				(justify mirror)
			)
		)
		(property "Value" ""
			(at 0 0 0)
			(layer "B.Fab")
			(effects
				(font
					(size 1.27 1.27)
				)
				(justify mirror)
			)
		)
		(duplicate_pad_numbers_are_jumpers no)
		(fp_poly
			(pts
				(xy 0.4953 -0.2032) (xy -0.4953 -0.2032) (xy -0.4953 1.6002) (xy 0.4953 1.6002)
			)
			(stroke
				(width 0)
				(type default)
			)
			(fill no)
			(layer "B.CrtYd")
		)
		(fp_line
			(start -0.4953 -0.2032)
			(end -0.4953 1.6002)
			(stroke
				(width 0.1)
				(type default)
			)
			(layer "B.Fab")
		)
		(fp_line
			(start -0.4953 1.6002)
			(end 0.4953 1.6002)
			(stroke
				(width 0.1)
				(type default)
			)
			(layer "B.Fab")
		)
		(fp_line
			(start 0.4953 -0.2032)
			(end -0.4953 -0.2032)
			(stroke
				(width 0.1)
				(type default)
			)
			(layer "B.Fab")
		)
		(fp_line
			(start 0.4953 1.6002)
			(end 0.4953 -0.2032)
			(stroke
				(width 0.1)
				(type default)
			)
			(layer "B.Fab")
		)
		(pad "1" smd rect
			(at 0 0 180)
			(size 0.762 0.889)
			(layers "B.Cu" "B.Mask" "B.Paste")
			(net "P3V3_STBY")
		)
		(pad "2" smd rect
			(at 0 1.397 180)
			(size 0.762 0.889)
			(layers "B.Cu" "B.Mask" "B.Paste")
			(net "GND")
		)
		(zone
			(layer "B.Cu")
			(hatch none 0.5)
			(connect_pads
				(clearance 0)
			)
			(min_thickness 0.25)
			(keepout
				(tracks not_allowed)
				(vias allowed)
				(pads allowed)
				(copperpour not_allowed)
				(footprints allowed)
			)
			(placement
				(enabled no)
				(sheetname "")
			)
			(fill
				(thermal_gap 0.5)
				(thermal_bridge_width 0.5)
				(island_removal_mode 0)
			)
			(polygon
				(pts
					(xy 464.71586 -40.73652) (xy 463.95386 -40.73652) (xy 463.95386 -40.22852) (xy 464.71586 -40.22852)
				)
			)
		)
	)
	(footprint ""
		(layer "B.Cu")
		(at 25.9842 -85.9028 90)
		(property "Reference" "R9P5"
			(at 0 0 90)
			(layer "B.SilkS")
			(hide yes)
			(effects
				(font
					(size 1.27 1.27)
				)
				(justify mirror)
			)
		)
		(property "Value" ""
			(at 0 0 90)
			(layer "B.Fab")
			(effects
				(font
					(size 1.27 1.27)
				)
				(justify mirror)
			)
		)
		(duplicate_pad_numbers_are_jumpers no)
		(fp_poly
			(pts
				(xy 0.2794 -0.1016) (xy -0.2794 -0.1016) (xy -0.2794 0.9906) (xy 0.2794 0.9906)
			)
			(stroke
				(width 0)
				(type default)
			)
			(fill no)
			(layer "B.CrtYd")
		)
		(fp_line
			(start 0.2794 -0.1016)
			(end 0.2794 0.9906)
			(stroke
				(width 0.1)
				(type default)
			)
			(layer "B.Fab")
		)
		(fp_line
			(start -0.2794 -0.1016)
			(end 0.2794 -0.1016)
			(stroke
				(width 0.1)
				(type default)
			)
			(layer "B.Fab")
		)
		(fp_line
			(start 0.2794 0.9906)
			(end -0.2794 0.9906)
			(stroke
				(width 0.1)
				(type default)
			)
			(layer "B.Fab")
		)
		(fp_line
			(start -0.2794 0.9906)
			(end -0.2794 -0.1016)
			(stroke
				(width 0.1)
				(type default)
			)
			(layer "B.Fab")
		)
		(pad "1" smd rect
			(at 0 0 270)
			(size 0.508 0.508)
			(layers "B.Cu" "B.Mask" "B.Paste")
			(net "P3V3_STBY")
		)
		(pad "2" smd rect
			(at 0 0.889 270)
			(size 0.508 0.508)
			(layers "B.Cu" "B.Mask" "B.Paste")
			(net "FM_DISABLE_FAN_N")
		)
		(zone
			(layer "B.Cu")
			(hatch none 0.5)
			(connect_pads
				(clearance 0)
			)
			(min_thickness 0.25)
			(keepout
				(tracks allowed)
				(vias not_allowed)
				(pads allowed)
				(copperpour not_allowed)
				(footprints allowed)
			)
			(placement
				(enabled no)
				(sheetname "")
			)
			(fill
				(thermal_gap 0.5)
				(thermal_bridge_width 0.5)
				(island_removal_mode 0)
			)
			(polygon
				(pts
					(xy 26.2382 -86.1568) (xy 26.2382 -85.6488) (xy 26.6192 -85.6488) (xy 26.6192 -86.1568)
				)
			)
		)
		(zone
			(layer "B.Cu")
			(hatch none 0.5)
			(connect_pads
				(clearance 0)
			)
			(min_thickness 0.25)
			(keepout
				(tracks not_allowed)
				(vias allowed)
				(pads allowed)
				(copperpour not_allowed)
				(footprints allowed)
			)
			(placement
				(enabled no)
				(sheetname "")
			)
			(fill
				(thermal_gap 0.5)
				(thermal_bridge_width 0.5)
				(island_removal_mode 0)
			)
			(polygon
				(pts
					(xy 26.6192 -86.1568) (xy 26.6192 -85.6488) (xy 26.2382 -85.6488) (xy 26.2382 -86.1568)
				)
			)
		)
	)
	(footprint ""
		(layer "B.Cu")
		(at 486.41 -111.94542 -90)
		(property "Reference" "C1M27"
			(at 0 0 90)
			(layer "B.SilkS")
			(hide yes)
			(effects
				(font
					(size 1.27 1.27)
				)
				(justify mirror)
			)
		)
		(property "Value" ""
			(at 0 0 90)
			(layer "B.Fab")
			(effects
				(font
					(size 1.27 1.27)
				)
				(justify mirror)
			)
		)
		(duplicate_pad_numbers_are_jumpers no)
		(fp_rect
			(start 0.7239 1.9939)
			(end -0.7239 -0.2159)
			(stroke
				(width 0)
				(type default)
			)
			(fill no)
			(layer "B.CrtYd")
		)
		(fp_line
			(start -0.7239 1.9939)
			(end -0.7239 -0.2159)
			(stroke
				(width 0.1)
				(type default)
			)
			(layer "B.Fab")
		)
		(fp_line
			(start 0.7239 1.9939)
			(end -0.7239 1.9939)
			(stroke
				(width 0.1)
				(type default)
			)
			(layer "B.Fab")
		)
		(fp_line
			(start -0.7239 -0.2159)
			(end 0.7239 -0.2159)
			(stroke
				(width 0.1)
				(type default)
			)
			(layer "B.Fab")
		)
		(fp_line
			(start 0.7239 -0.2159)
			(end 0.7239 1.9939)
			(stroke
				(width 0.1)
				(type default)
			)
			(layer "B.Fab")
		)
		(pad "1" smd rect
			(at 0 0 90)
			(size 1.27 1.016)
			(layers "B.Cu" "B.Mask" "B.Paste")
			(net "P12V_STBY")
		)
		(pad "2" smd rect
			(at 0 1.778 90)
			(size 1.27 1.016)
			(layers "B.Cu" "B.Mask" "B.Paste")
			(net "GND")
		)
		(zone
			(layer "B.Cu")
			(hatch none 0.5)
			(connect_pads
				(clearance 0)
			)
			(min_thickness 0.25)
			(keepout
				(tracks not_allowed)
				(vias allowed)
				(pads allowed)
				(copperpour not_allowed)
				(footprints allowed)
			)
			(placement
				(enabled no)
				(sheetname "")
			)
			(fill
				(thermal_gap 0.5)
				(thermal_bridge_width 0.5)
				(island_removal_mode 0)
			)
			(polygon
				(pts
					(xy 485.14 -111.31042) (xy 485.902 -111.31042) (xy 485.902 -112.58042) (xy 485.14 -112.58042)
				)
			)
		)
	)
)
